# T6G (Grand Teton) — schematic netlist excerpt (pin names and nets, part order shuffled) for the footprints in the layout excerpt that follows; sources: Cadence DE-HDL packaged netlist, KiCad conversion of 04192023_DAF0TMB3IC0_F0TG_MB_C_brd_V02_OCP.brd

R408  Q_RES  2.2K 5% CHIP  pkg 0402LF  page 27 : A = CPU0_BP0 ; B = PVDD18_S5_P0
C58  Q_CAP  0.1UF 25V 10% X7R  pkg 0402  page 183 : A = P3V3_9ZXL045_P1_VDD ; B = GND

(kicad_pcb
	(version 20260206)
	(generator "pcbnew")
	(generator_version "10.0")
	(general
		(thickness 1.6)
		(legacy_teardrops no)
	)
	(paper "A4")
	(title_block
		(title "04192023_DAF0TMB3IC0_F0TG_MB_C_brd_V02_OCP.brd")
		(comment 1 "Grand Teton / footprints 7158-7159 of 8354")
	)
	(layers
		(0 "F.Cu" signal "TOP")
		(4 "In1.Cu" signal "GND")
		(6 "In2.Cu" signal "IN1")
		(8 "In3.Cu" signal "GND1")
		(10 "In4.Cu" signal "IN2")
		(12 "In5.Cu" signal "GND2")
		(14 "In6.Cu" signal "IN3")
		(16 "In7.Cu" signal "GND3")
		(18 "In8.Cu" signal "VCC")
		(20 "In9.Cu" signal "VCC1")
		(22 "In10.Cu" signal "GND4")
		(24 "In11.Cu" signal "IN4")
		(26 "In12.Cu" signal "GND5")
		(28 "In13.Cu" signal "IN5")
		(30 "In14.Cu" signal "GND6")
		(32 "In15.Cu" signal "IN6")
		(34 "In16.Cu" signal "GND7")
		(2 "B.Cu" signal "BOTTOM")
		(9 "F.Adhes" user "F.Adhesive")
		(11 "B.Adhes" user "B.Adhesive")
		(13 "F.Paste" user "Package Geometry/Pastemask Top")
		(15 "B.Paste" user "Package Geometry/Pastemask Bottom")
		(5 "F.SilkS" user "Ref Des/Silkscreen Top")
		(7 "B.SilkS" user "Ref Des/Silkscreen Bottom")
		(1 "F.Mask" user "Board Geometry/Soldermask Top")
		(3 "B.Mask" user "Board Geometry/Soldermask Bottom")
		(17 "Dwgs.User" user "User.Drawings")
		(19 "Cmts.User" user "User.Comments")
		(21 "Eco1.User" user "User.Eco1")
		(23 "Eco2.User" user "User.Eco2")
		(25 "Edge.Cuts" user "Board Geometry/Outline")
		(27 "Margin" user)
		(31 "F.CrtYd" user "Package Geometry/Place Bound Top")
		(29 "B.CrtYd" user "Package Geometry/Place Bound Bottom")
		(35 "F.Fab" user "Ref Des/Assembly Top")
		(33 "B.Fab" user "Ref Des/Assembly Bottom")
	)
	(footprint ""
		(layer "B.Cu")
		(at 320.846958 -198.583296)
		(property "Reference" "R408"
			(at 0 0 0)
			(layer "B.SilkS")
			(hide yes)
			(effects
				(font
					(size 1.27 1.27)
				)
				(justify mirror)
			)
		)
		(property "Value" ""
			(at 0 0 0)
			(layer "B.Fab")
			(effects
				(font
					(size 1.27 1.27)
				)
				(justify mirror)
			)
		)
		(duplicate_pad_numbers_are_jumpers no)
		(fp_line
			(start -0.7874 -0.4064)
			(end -0.7874 0.4064)
			(stroke
				(width 0.1524)
				(type default)
			)
			(layer "B.SilkS")
		)
		(fp_line
			(start -0.7874 0.4064)
			(end 0.7874 0.4064)
			(stroke
				(width 0.1524)
				(type default)
			)
			(layer "B.SilkS")
		)
		(fp_line
			(start 0.7874 -0.4064)
			(end -0.7874 -0.4064)
			(stroke
				(width 0.1524)
				(type default)
			)
			(layer "B.SilkS")
		)
		(fp_line
			(start 0.7874 0.4064)
			(end 0.7874 -0.4064)
			(stroke
				(width 0.1524)
				(type default)
			)
			(layer "B.SilkS")
		)
		(fp_line
			(start -0.67945 -0.3048)
			(end -0.67945 0.3048)
			(stroke
				(width 0.1)
				(type default)
			)
			(layer "B.Fab")
		)
		(fp_line
			(start -0.67945 0.3048)
			(end -0.120396 0.3048)
			(stroke
				(width 0.1)
				(type default)
			)
			(layer "B.Fab")
		)
		(fp_line
			(start -0.12065 -0.3048)
			(end -0.67945 -0.3048)
			(stroke
				(width 0.1)
				(type default)
			)
			(layer "B.Fab")
		)
		(fp_line
			(start -0.12065 -0.2794)
			(end -0.12065 -0.3048)
			(stroke
				(width 0.1)
				(type default)
			)
			(layer "B.Fab")
		)
		(fp_line
			(start -0.120396 0.2794)
			(end 0.12065 0.2794)
			(stroke
				(width 0.1)
				(type default)
			)
			(layer "B.Fab")
		)
		(fp_line
			(start -0.120396 0.3048)
			(end -0.120396 0.2794)
			(stroke
				(width 0.1)
				(type default)
			)
			(layer "B.Fab")
		)
		(fp_line
			(start 0.12065 -0.305054)
			(end 0.12065 -0.2794)
			(stroke
				(width 0.1)
				(type default)
			)
			(layer "B.Fab")
		)
		(fp_line
			(start 0.12065 -0.2794)
			(end -0.12065 -0.2794)
			(stroke
				(width 0.1)
				(type default)
			)
			(layer "B.Fab")
		)
		(fp_line
			(start 0.12065 0.2794)
			(end 0.12065 0.3048)
			(stroke
				(width 0.1)
				(type default)
			)
			(layer "B.Fab")
		)
		(fp_line
			(start 0.12065 0.3048)
			(end 0.67945 0.3048)
			(stroke
				(width 0.1)
				(type default)
			)
			(layer "B.Fab")
		)
		(fp_line
			(start 0.67945 -0.305054)
			(end 0.12065 -0.305054)
			(stroke
				(width 0.1)
				(type default)
			)
			(layer "B.Fab")
		)
		(fp_line
			(start 0.67945 0.3048)
			(end 0.67945 -0.305054)
			(stroke
				(width 0.1)
				(type default)
			)
			(layer "B.Fab")
		)
		(pad "1" smd circle
			(at 0.40005 0 180)
			(size 0 0)
			(layers "B.Cu" "B.Mask" "B.Paste")
			(net "CPU0_BP0")
		)
		(pad "2" smd circle
			(at -0.40005 0 180)
			(size 0 0)
			(layers "B.Cu" "B.Mask" "B.Paste")
			(net "PVDD18_S5_P0")
		)
	)
	(footprint ""
		(layer "B.Cu")
		(at 108.833158 -408.52598)
		(property "Reference" "C58"
			(at 0 0 0)
			(layer "B.SilkS")
			(hide yes)
			(effects
				(font
					(size 1.27 1.27)
				)
				(justify mirror)
			)
		)
		(property "Value" ""
			(at 0 0 0)
			(layer "B.Fab")
			(effects
				(font
					(size 1.27 1.27)
				)
				(justify mirror)
			)
		)
		(duplicate_pad_numbers_are_jumpers no)
		(fp_line
			(start -0.7874 -0.4064)
			(end -0.7874 0.4064)
			(stroke
				(width 0.1524)
				(type default)
			)
			(layer "B.SilkS")
		)
		(fp_line
			(start -0.7874 0.4064)
			(end 0.7874 0.4064)
			(stroke
				(width 0.1524)
				(type default)
			)
			(layer "B.SilkS")
		)
		(fp_line
			(start 0.7874 -0.4064)
			(end -0.7874 -0.4064)
			(stroke
				(width 0.1524)
				(type default)
			)
			(layer "B.SilkS")
		)
		(fp_line
			(start 0.7874 0.4064)
			(end 0.7874 -0.4064)
			(stroke
				(width 0.1524)
				(type default)
			)
			(layer "B.SilkS")
		)
		(fp_line
			(start -0.67945 -0.3048)
			(end -0.67945 0.3048)
			(stroke
				(width 0.1)
				(type default)
			)
			(layer "B.Fab")
		)
		(fp_line
			(start -0.67945 0.3048)
			(end -0.120396 0.3048)
			(stroke
				(width 0.1)
				(type default)
			)
			(layer "B.Fab")
		)
		(fp_line
			(start -0.12065 -0.3048)
			(end -0.67945 -0.3048)
			(stroke
				(width 0.1)
				(type default)
			)
			(layer "B.Fab")
		)
		(fp_line
			(start -0.12065 -0.2794)
			(end -0.12065 -0.3048)
			(stroke
				(width 0.1)
				(type default)
			)
			(layer "B.Fab")
		)
		(fp_line
			(start -0.120396 0.2794)
			(end 0.12065 0.2794)
			(stroke
				(width 0.1)
				(type default)
			)
			(layer "B.Fab")
		)
		(fp_line
			(start -0.120396 0.3048)
			(end -0.120396 0.2794)
			(stroke
				(width 0.1)
				(type default)
			)
			(layer "B.Fab")
		)
		(fp_line
			(start 0.12065 -0.305054)
			(end 0.12065 -0.2794)
			(stroke
				(width 0.1)
				(type default)
			)
			(layer "B.Fab")
		)
		(fp_line
			(start 0.12065 -0.2794)
			(end -0.12065 -0.2794)
			(stroke
				(width 0.1)
				(type default)
			)
			(layer "B.Fab")
		)
		(fp_line
			(start 0.12065 0.2794)
			(end 0.12065 0.3048)
			(stroke
				(width 0.1)
				(type default)
			)
			(layer "B.Fab")
		)
		(fp_line
			(start 0.12065 0.3048)
			(end 0.67945 0.3048)
			(stroke
				(width 0.1)
				(type default)
			)
			(layer "B.Fab")
		)
		(fp_line
			(start 0.67945 -0.305054)
			(end 0.12065 -0.305054)
			(stroke
				(width 0.1)
				(type default)
			)
			(layer "B.Fab")
		)
		(fp_line
			(start 0.67945 0.3048)
			(end 0.67945 -0.305054)
			(stroke
				(width 0.1)
				(type default)
			)
			(layer "B.Fab")
		)
		(pad "1" smd circle
			(at 0.40005 0 180)
			(size 0 0)
			(layers "B.Cu" "B.Mask" "B.Paste")
			(net "P3V3_9ZXL045_P1_VDD")
		)
		(pad "2" smd circle
			(at -0.40005 0 180)
			(size 0 0)
			(layers "B.Cu" "B.Mask" "B.Paste")
			(net "GND")
		)
	)
)
